# T6G (Grand Teton) — schematic netlist excerpt (pin names and nets, part order shuffled) for the footprints in the layout excerpt that follows; sources: Cadence DE-HDL packaged netlist, KiCad conversion of 04192023_DAF0TMB3IC0_F0TG_MB_C_brd_V02_OCP.brd

C6100  Q_CAP  0.01UF 50V 10% X7R  pkg C0402  page 179 : A = P3V3_AUX_CPU0_USB2_AVDD33 ; B = GND
C2553  Q_CAP  22UF 4V 20% X6S  pkg C0402  page 70 : A = PVDDCR_SOC_P0 ; B = GND

(kicad_pcb
	(version 20260206)
	(generator "pcbnew")
	(generator_version "10.0")
	(general
		(thickness 1.6)
		(legacy_teardrops no)
	)
	(paper "A4")
	(title_block
		(title "04192023_DAF0TMB3IC0_F0TG_MB_C_brd_V02_OCP.brd")
		(comment 1 "Grand Teton / footprints 6519-6520 of 8354")
	)
	(layers
		(0 "F.Cu" signal "TOP")
		(4 "In1.Cu" signal "GND")
		(6 "In2.Cu" signal "IN1")
		(8 "In3.Cu" signal "GND1")
		(10 "In4.Cu" signal "IN2")
		(12 "In5.Cu" signal "GND2")
		(14 "In6.Cu" signal "IN3")
		(16 "In7.Cu" signal "GND3")
		(18 "In8.Cu" signal "VCC")
		(20 "In9.Cu" signal "VCC1")
		(22 "In10.Cu" signal "GND4")
		(24 "In11.Cu" signal "IN4")
		(26 "In12.Cu" signal "GND5")
		(28 "In13.Cu" signal "IN5")
		(30 "In14.Cu" signal "GND6")
		(32 "In15.Cu" signal "IN6")
		(34 "In16.Cu" signal "GND7")
		(2 "B.Cu" signal "BOTTOM")
		(9 "F.Adhes" user "F.Adhesive")
		(11 "B.Adhes" user "B.Adhesive")
		(13 "F.Paste" user "Package Geometry/Pastemask Top")
		(15 "B.Paste" user "Package Geometry/Pastemask Bottom")
		(5 "F.SilkS" user "Ref Des/Silkscreen Top")
		(7 "B.SilkS" user "Ref Des/Silkscreen Bottom")
		(1 "F.Mask" user "Board Geometry/Soldermask Top")
		(3 "B.Mask" user "Board Geometry/Soldermask Bottom")
		(17 "Dwgs.User" user "User.Drawings")
		(19 "Cmts.User" user "User.Comments")
		(21 "Eco1.User" user "User.Eco1")
		(23 "Eco2.User" user "User.Eco2")
		(25 "Edge.Cuts" user "Board Geometry/Outline")
		(27 "Margin" user)
		(31 "F.CrtYd" user "Package Geometry/Place Bound Top")
		(29 "B.CrtYd" user "Package Geometry/Place Bound Bottom")
		(35 "F.Fab" user "Ref Des/Assembly Top")
		(33 "B.Fab" user "Ref Des/Assembly Bottom")
	)
	(footprint ""
		(layer "B.Cu")
		(at 358.465882 -256.012188 -90)
		(property "Reference" "C2553"
			(at 0 0 90)
			(layer "B.SilkS")
			(hide yes)
			(effects
				(font
					(size 1.27 1.27)
				)
				(justify mirror)
			)
		)
		(property "Value" ""
			(at 0 0 90)
			(layer "B.Fab")
			(effects
				(font
					(size 1.27 1.27)
				)
				(justify mirror)
			)
		)
		(duplicate_pad_numbers_are_jumpers no)
		(fp_line
			(start -0.7874 0.4064)
			(end 0.7874 0.4064)
			(stroke
				(width 0.1524)
				(type default)
			)
			(layer "B.SilkS")
		)
		(fp_line
			(start 0.7874 0.4064)
			(end 0.7874 -0.4064)
			(stroke
				(width 0.1524)
				(type default)
			)
			(layer "B.SilkS")
		)
		(fp_line
			(start -0.7874 -0.4064)
			(end -0.7874 0.4064)
			(stroke
				(width 0.1524)
				(type default)
			)
			(layer "B.SilkS")
		)
		(fp_line
			(start 0.7874 -0.4064)
			(end -0.7874 -0.4064)
			(stroke
				(width 0.1524)
				(type default)
			)
			(layer "B.SilkS")
		)
		(fp_line
			(start -0.67945 0.3048)
			(end -0.120396 0.3048)
			(stroke
				(width 0.1)
				(type default)
			)
			(layer "B.Fab")
		)
		(fp_line
			(start -0.120396 0.3048)
			(end -0.120396 0.2794)
			(stroke
				(width 0.1)
				(type default)
			)
			(layer "B.Fab")
		)
		(fp_line
			(start 0.12065 0.3048)
			(end 0.67945 0.3048)
			(stroke
				(width 0.1)
				(type default)
			)
			(layer "B.Fab")
		)
		(fp_line
			(start 0.67945 0.3048)
			(end 0.67945 -0.305054)
			(stroke
				(width 0.1)
				(type default)
			)
			(layer "B.Fab")
		)
		(fp_line
			(start -0.120396 0.2794)
			(end 0.12065 0.2794)
			(stroke
				(width 0.1)
				(type default)
			)
			(layer "B.Fab")
		)
		(fp_line
			(start 0.12065 0.2794)
			(end 0.12065 0.3048)
			(stroke
				(width 0.1)
				(type default)
			)
			(layer "B.Fab")
		)
		(fp_line
			(start -0.12065 -0.2794)
			(end -0.12065 -0.3048)
			(stroke
				(width 0.1)
				(type default)
			)
			(layer "B.Fab")
		)
		(fp_line
			(start 0.12065 -0.2794)
			(end -0.12065 -0.2794)
			(stroke
				(width 0.1)
				(type default)
			)
			(layer "B.Fab")
		)
		(fp_line
			(start -0.67945 -0.3048)
			(end -0.67945 0.3048)
			(stroke
				(width 0.1)
				(type default)
			)
			(layer "B.Fab")
		)
		(fp_line
			(start -0.12065 -0.3048)
			(end -0.67945 -0.3048)
			(stroke
				(width 0.1)
				(type default)
			)
			(layer "B.Fab")
		)
		(fp_line
			(start 0.12065 -0.305054)
			(end 0.12065 -0.2794)
			(stroke
				(width 0.1)
				(type default)
			)
			(layer "B.Fab")
		)
		(fp_line
			(start 0.67945 -0.305054)
			(end 0.12065 -0.305054)
			(stroke
				(width 0.1)
				(type default)
			)
			(layer "B.Fab")
		)
		(pad "1" smd circle
			(at 0.40005 0 90)
			(size 0 0)
			(layers "B.Cu" "B.Mask" "B.Paste")
			(net "PVDDCR_SOC_P0")
		)
		(pad "2" smd circle
			(at -0.40005 0 90)
			(size 0 0)
			(layers "B.Cu" "B.Mask" "B.Paste")
			(net "GND")
		)
	)
	(footprint ""
		(layer "B.Cu")
		(at 107.917996 -26.952448 90)
		(property "Reference" "C6100"
			(at 0 0 90)
			(layer "B.SilkS")
			(hide yes)
			(effects
				(font
					(size 1.27 1.27)
				)
				(justify mirror)
			)
		)
		(property "Value" ""
			(at 0 0 90)
			(layer "B.Fab")
			(effects
				(font
					(size 1.27 1.27)
				)
				(justify mirror)
			)
		)
		(duplicate_pad_numbers_are_jumpers no)
		(fp_line
			(start 0.7874 -0.4064)
			(end -0.7874 -0.4064)
			(stroke
				(width 0.1524)
				(type default)
			)
			(layer "B.SilkS")
		)
		(fp_line
			(start -0.7874 -0.4064)
			(end -0.7874 0.4064)
			(stroke
				(width 0.1524)
				(type default)
			)
			(layer "B.SilkS")
		)
		(fp_line
			(start 0.7874 0.4064)
			(end 0.7874 -0.4064)
			(stroke
				(width 0.1524)
				(type default)
			)
			(layer "B.SilkS")
		)
		(fp_line
			(start -0.7874 0.4064)
			(end 0.7874 0.4064)
			(stroke
				(width 0.1524)
				(type default)
			)
			(layer "B.SilkS")
		)
		(fp_line
			(start 0.67945 -0.305054)
			(end 0.12065 -0.305054)
			(stroke
				(width 0.1)
				(type default)
			)
			(layer "B.Fab")
		)
		(fp_line
			(start 0.12065 -0.305054)
			(end 0.12065 -0.2794)
			(stroke
				(width 0.1)
				(type default)
			)
			(layer "B.Fab")
		)
		(fp_line
			(start -0.12065 -0.3048)
			(end -0.67945 -0.3048)
			(stroke
				(width 0.1)
				(type default)
			)
			(layer "B.Fab")
		)
		(fp_line
			(start -0.67945 -0.3048)
			(end -0.67945 0.3048)
			(stroke
				(width 0.1)
				(type default)
			)
			(layer "B.Fab")
		)
		(fp_line
			(start 0.12065 -0.2794)
			(end -0.12065 -0.2794)
			(stroke
				(width 0.1)
				(type default)
			)
			(layer "B.Fab")
		)
		(fp_line
			(start -0.12065 -0.2794)
			(end -0.12065 -0.3048)
			(stroke
				(width 0.1)
				(type default)
			)
			(layer "B.Fab")
		)
		(fp_line
			(start 0.12065 0.2794)
			(end 0.12065 0.3048)
			(stroke
				(width 0.1)
				(type default)
			)
			(layer "B.Fab")
		)
		(fp_line
			(start -0.120396 0.2794)
			(end 0.12065 0.2794)
			(stroke
				(width 0.1)
				(type default)
			)
			(layer "B.Fab")
		)
		(fp_line
			(start 0.67945 0.3048)
			(end 0.67945 -0.305054)
			(stroke
				(width 0.1)
				(type default)
			)
			(layer "B.Fab")
		)
		(fp_line
			(start 0.12065 0.3048)
			(end 0.67945 0.3048)
			(stroke
				(width 0.1)
				(type default)
			)
			(layer "B.Fab")
		)
		(fp_line
			(start -0.120396 0.3048)
			(end -0.120396 0.2794)
			(stroke
				(width 0.1)
				(type default)
			)
			(layer "B.Fab")
		)
		(fp_line
			(start -0.67945 0.3048)
			(end -0.120396 0.3048)
			(stroke
				(width 0.1)
				(type default)
			)
			(layer "B.Fab")
		)
		(pad "1" smd circle
			(at 0.40005 0 270)
			(size 0 0)
			(layers "B.Cu" "B.Mask" "B.Paste")
			(net "P3V3_AUX_CPU0_USB2_AVDD33")
		)
		(pad "2" smd circle
			(at -0.40005 0 270)
			(size 0 0)
			(layers "B.Cu" "B.Mask" "B.Paste")
			(net "GND")
		)
	)
)
